(kicad_pcb
	(version 20260206)
	(generator "pcbnew")
	(generator_version "10.0")
	(general
		(thickness 1.6)
		(legacy_teardrops no)
	)
	(paper "A4")
	(title_block
		(title "panther-plus-userver — 13130-1b_20150205.brd")
		(comment 1 "Honey Badger (Wiwynn) / footprints 1449-1452 of 1509")
	)
	(layers
		(0 "F.Cu" signal "TOP")
		(4 "In1.Cu" signal "L2")
		(6 "In2.Cu" signal "L3")
		(8 "In3.Cu" signal "L4")
		(10 "In4.Cu" signal "L5")
		(12 "In5.Cu" signal "L6")
		(14 "In6.Cu" signal "L7")
		(16 "In7.Cu" signal "L8")
		(18 "In8.Cu" signal "L9")
		(20 "In9.Cu" signal "L10")
		(22 "In10.Cu" signal "L11")
		(2 "B.Cu" signal "BOTTOM")
		(9 "F.Adhes" user "F.Adhesive")
		(11 "B.Adhes" user "B.Adhesive")
		(13 "F.Paste" user "Package Geometry/Pastemask Top")
		(15 "B.Paste" user "Package Geometry/Pastemask Bottom")
		(5 "F.SilkS" user "Ref Des/Silkscreen Top")
		(7 "B.SilkS" user "Ref Des/Silkscreen Bottom")
		(1 "F.Mask" user "Board Geometry/Soldermask Top")
		(3 "B.Mask" user "Board Geometry/Soldermask Bottom")
		(17 "Dwgs.User" user "User.Drawings")
		(19 "Cmts.User" user "User.Comments")
		(21 "Eco1.User" user "User.Eco1")
		(23 "Eco2.User" user "User.Eco2")
		(25 "Edge.Cuts" user "Board Geometry/Outline")
		(27 "Margin" user)
		(31 "F.CrtYd" user "Package Geometry/Place Bound Top")
		(29 "B.CrtYd" user "Package Geometry/Place Bound Bottom")
		(35 "F.Fab" user "Ref Des/Assembly Top")
		(33 "B.Fab" user "Ref Des/Assembly Bottom")
	)
	(footprint ""
		(layer "B.Cu")
		(at 41.402 -42.291)
		(property "Reference" "R120"
			(at 0 0 0)
			(layer "B.SilkS")
			(hide yes)
			(effects
				(font
					(size 1.27 1.27)
				)
				(justify mirror)
			)
		)
		(property "Value" "0R2J-2-GP"
			(at -0.064008 -3.993896 0)
			(unlocked yes)
			(layer "B.Fab")
			(hide yes)
			(effects
				(font
					(size 1.016 1.016)
					(thickness 0.1524)
				)
				(justify mirror)
			)
		)
		(property "Device Type" "R402H16"
			(at -0.064008 -5.517896 0)
			(unlocked yes)
			(layer "B.Fab")
			(hide yes)
			(effects
				(font
					(size 1.016 1.016)
					(thickness 0.1524)
				)
				(justify mirror)
			)
		)
		(duplicate_pad_numbers_are_jumpers no)
		(fp_rect
			(start 0.381 0.8382)
			(end -0.381 -0.8382)
			(stroke
				(width 0)
				(type default)
			)
			(fill no)
			(layer "B.CrtYd")
		)
		(fp_rect
			(start 0.381 0.8382)
			(end -0.381 -0.8382)
			(stroke
				(width 0)
				(type default)
			)
			(fill no)
			(layer "B.Fab")
		)
		(pad "1" smd custom
			(at 0 -0.4318 180)
			(size 0.127 0.127)
			(layers "B.Cu" "B.Mask" "B.Paste")
			(net "CLK_GEN_R_PG")
			(options
				(clearance outline)
				(anchor circle)
			)
			(primitives
				(gr_poly
					(pts
						(arc
							(start -0.2032 0.2794)
							(mid -0.239121 0.264521)
							(end -0.254 0.2286)
						)
						(arc
							(start -0.254 -0.2286)
							(mid -0.239121 -0.264521)
							(end -0.2032 -0.2794)
						)
						(arc
							(start 0.2032 -0.2794)
							(mid 0.239121 -0.264521)
							(end 0.254 -0.2286)
						)
						(arc
							(start 0.254 0.2286)
							(mid 0.239121 0.264521)
							(end 0.2032 0.2794)
						)
					)
					(width 0)
					(fill yes)
				)
			)
		)
		(pad "2" smd custom
			(at 0 0.4318 180)
			(size 0.127 0.127)
			(layers "B.Cu" "B.Mask" "B.Paste")
			(net "CLK_GEN_PG")
			(options
				(clearance outline)
				(anchor circle)
			)
			(primitives
				(gr_poly
					(pts
						(arc
							(start -0.2032 0.2794)
							(mid -0.239121 0.264521)
							(end -0.254 0.2286)
						)
						(arc
							(start -0.254 -0.2286)
							(mid -0.239121 -0.264521)
							(end -0.2032 -0.2794)
						)
						(arc
							(start 0.2032 -0.2794)
							(mid 0.239121 -0.264521)
							(end 0.254 -0.2286)
						)
						(arc
							(start 0.254 0.2286)
							(mid 0.239121 0.264521)
							(end 0.2032 0.2794)
						)
					)
					(width 0)
					(fill yes)
				)
			)
		)
	)
	(footprint ""
		(layer "B.Cu")
		(at 133.731 -37.719 -90)
		(property "Reference" "C136"
			(at 0 0 90)
			(layer "B.SilkS")
			(hide yes)
			(effects
				(font
					(size 1.27 1.27)
				)
				(justify mirror)
			)
		)
		(property "Value" "SCD1U10V2KX-5GP"
			(at -1.1811 -2.7051 270)
			(unlocked yes)
			(layer "B.Fab")
			(hide yes)
			(effects
				(font
					(size 1.016 1.016)
					(thickness 0.1524)
				)
				(justify mirror)
			)
		)
		(property "Device Type" "C402H22"
			(at -1.1811 -4.2291 270)
			(unlocked yes)
			(layer "B.Fab")
			(hide yes)
			(effects
				(font
					(size 1.016 1.016)
					(thickness 0.1524)
				)
				(justify mirror)
			)
		)
		(duplicate_pad_numbers_are_jumpers no)
		(fp_rect
			(start 0.381 0.7366)
			(end -0.381 -0.7366)
			(stroke
				(width 0)
				(type default)
			)
			(fill no)
			(layer "B.CrtYd")
		)
		(fp_rect
			(start 0.381 0.7366)
			(end -0.381 -0.7366)
			(stroke
				(width 0)
				(type default)
			)
			(fill no)
			(layer "B.Fab")
		)
		(pad "1" smd custom
			(at 0 -0.4572 90)
			(size 0.1143 0.1143)
			(layers "B.Cu" "B.Mask" "B.Paste")
			(net "P3V3_STBY")
			(options
				(clearance outline)
				(anchor circle)
			)
			(primitives
				(gr_poly
					(pts
						(arc
							(start -0.254 0.1778)
							(mid -0.239121 0.213721)
							(end -0.2032 0.2286)
						)
						(arc
							(start 0.2032 0.2286)
							(mid 0.239121 0.213721)
							(end 0.254 0.1778)
						)
						(arc
							(start 0.254 -0.1778)
							(mid 0.239121 -0.213721)
							(end 0.2032 -0.2286)
						)
						(arc
							(start -0.2032 -0.2286)
							(mid -0.239121 -0.213721)
							(end -0.254 -0.1778)
						)
					)
					(width 0)
					(fill yes)
				)
			)
		)
		(pad "2" smd custom
			(at 0 0.4572 90)
			(size 0.1143 0.1143)
			(layers "B.Cu" "B.Mask" "B.Paste")
			(net "GND")
			(options
				(clearance outline)
				(anchor circle)
			)
			(primitives
				(gr_poly
					(pts
						(arc
							(start -0.254 0.1778)
							(mid -0.239121 0.213721)
							(end -0.2032 0.2286)
						)
						(arc
							(start 0.2032 0.2286)
							(mid 0.239121 0.213721)
							(end 0.254 0.1778)
						)
						(arc
							(start 0.254 -0.1778)
							(mid 0.239121 -0.213721)
							(end 0.2032 -0.2286)
						)
						(arc
							(start -0.2032 -0.2286)
							(mid -0.239121 -0.213721)
							(end -0.254 -0.1778)
						)
					)
					(width 0)
					(fill yes)
				)
			)
		)
	)
	(footprint ""
		(layer "B.Cu")
		(at 74.168 -40.767 90)
		(property "Reference" "R318"
			(at 0 0 90)
			(layer "B.SilkS")
			(hide yes)
			(effects
				(font
					(size 1.27 1.27)
				)
				(justify mirror)
			)
		)
		(property "Value" "4K7R2F-GP"
			(at -0.064008 -3.993896 90)
			(unlocked yes)
			(layer "B.Fab")
			(hide yes)
			(effects
				(font
					(size 1.016 1.016)
					(thickness 0.1524)
				)
				(justify mirror)
			)
		)
		(property "Device Type" "R402H16"
			(at -0.064008 -5.517896 90)
			(unlocked yes)
			(layer "B.Fab")
			(hide yes)
			(effects
				(font
					(size 1.016 1.016)
					(thickness 0.1524)
				)
				(justify mirror)
			)
		)
		(duplicate_pad_numbers_are_jumpers no)
		(fp_rect
			(start 0.381 0.8382)
			(end -0.381 -0.8382)
			(stroke
				(width 0)
				(type default)
			)
			(fill no)
			(layer "B.CrtYd")
		)
		(fp_rect
			(start 0.381 0.8382)
			(end -0.381 -0.8382)
			(stroke
				(width 0)
				(type default)
			)
			(fill no)
			(layer "B.Fab")
		)
		(pad "1" smd custom
			(at 0 -0.4318 270)
			(size 0.127 0.127)
			(layers "B.Cu" "B.Mask" "B.Paste")
			(net "P3V3")
			(options
				(clearance outline)
				(anchor circle)
			)
			(primitives
				(gr_poly
					(pts
						(arc
							(start -0.2032 0.2794)
							(mid -0.239121 0.264521)
							(end -0.254 0.2286)
						)
						(arc
							(start -0.254 -0.2286)
							(mid -0.239121 -0.264521)
							(end -0.2032 -0.2794)
						)
						(arc
							(start 0.2032 -0.2794)
							(mid 0.239121 -0.264521)
							(end 0.254 -0.2286)
						)
						(arc
							(start 0.254 0.2286)
							(mid 0.239121 0.264521)
							(end 0.2032 0.2794)
						)
					)
					(width 0)
					(fill yes)
				)
			)
		)
		(pad "2" smd custom
			(at 0 0.4318 270)
			(size 0.127 0.127)
			(layers "B.Cu" "B.Mask" "B.Paste")
			(net "BD_ID_1")
			(options
				(clearance outline)
				(anchor circle)
			)
			(primitives
				(gr_poly
					(pts
						(arc
							(start -0.2032 0.2794)
							(mid -0.239121 0.264521)
							(end -0.254 0.2286)
						)
						(arc
							(start -0.254 -0.2286)
							(mid -0.239121 -0.264521)
							(end -0.2032 -0.2794)
						)
						(arc
							(start 0.2032 -0.2794)
							(mid 0.239121 -0.264521)
							(end 0.254 -0.2286)
						)
						(arc
							(start 0.254 0.2286)
							(mid 0.239121 0.264521)
							(end 0.2032 0.2794)
						)
					)
					(width 0)
					(fill yes)
				)
			)
		)
	)
	(footprint ""
		(layer "B.Cu")
		(at 74.168 -40.005 -90)
		(property "Reference" "R323"
			(at 0 0 90)
			(layer "B.SilkS")
			(hide yes)
			(effects
				(font
					(size 1.27 1.27)
				)
				(justify mirror)
			)
		)
		(property "Value" "10KR2F-2-GP"
			(at -0.064008 -3.993896 270)
			(unlocked yes)
			(layer "B.Fab")
			(hide yes)
			(effects
				(font
					(size 1.016 1.016)
					(thickness 0.1524)
				)
				(justify mirror)
			)
		)
		(property "Device Type" "R402H16"
			(at -0.064008 -5.517896 270)
			(unlocked yes)
			(layer "B.Fab")
			(hide yes)
			(effects
				(font
					(size 1.016 1.016)
					(thickness 0.1524)
				)
				(justify mirror)
			)
		)
		(duplicate_pad_numbers_are_jumpers no)
		(fp_rect
			(start 0.381 0.8382)
			(end -0.381 -0.8382)
			(stroke
				(width 0)
				(type default)
			)
			(fill no)
			(layer "B.CrtYd")
		)
		(fp_rect
			(start 0.381 0.8382)
			(end -0.381 -0.8382)
			(stroke
				(width 0)
				(type default)
			)
			(fill no)
			(layer "B.Fab")
		)
		(pad "1" smd custom
			(at 0 -0.4318 90)
			(size 0.127 0.127)
			(layers "B.Cu" "B.Mask" "B.Paste")
			(net "CORE_PWROK")
			(options
				(clearance outline)
				(anchor circle)
			)
			(primitives
				(gr_poly
					(pts
						(arc
							(start -0.2032 0.2794)
							(mid -0.239121 0.264521)
							(end -0.254 0.2286)
						)
						(arc
							(start -0.254 -0.2286)
							(mid -0.239121 -0.264521)
							(end -0.2032 -0.2794)
						)
						(arc
							(start 0.2032 -0.2794)
							(mid 0.239121 -0.264521)
							(end 0.254 -0.2286)
						)
						(arc
							(start 0.254 0.2286)
							(mid 0.239121 0.264521)
							(end 0.2032 0.2794)
						)
					)
					(width 0)
					(fill yes)
				)
			)
		)
		(pad "2" smd custom
			(at 0 0.4318 90)
			(size 0.127 0.127)
			(layers "B.Cu" "B.Mask" "B.Paste")
			(net "GND")
			(options
				(clearance outline)
				(anchor circle)
			)
			(primitives
				(gr_poly
					(pts
						(arc
							(start -0.2032 0.2794)
							(mid -0.239121 0.264521)
							(end -0.254 0.2286)
						)
						(arc
							(start -0.254 -0.2286)
							(mid -0.239121 -0.264521)
							(end -0.2032 -0.2794)
						)
						(arc
							(start 0.2032 -0.2794)
							(mid 0.239121 -0.264521)
							(end 0.254 -0.2286)
						)
						(arc
							(start 0.254 0.2286)
							(mid 0.239121 0.264521)
							(end 0.2032 0.2794)
						)
					)
					(width 0)
					(fill yes)
				)
			)
		)
	)
)
